(kicad_pcb
	(version 20260206)
	(generator "pcbnew")
	(generator_version "10.0")
	(general
		(thickness 1.6)
		(legacy_teardrops no)
	)
	(paper "A4")
	(title_block
		(title "01162023_DA0F0TEBIF0_F0T_Expander_BD_F_brd_V02_OCP.brd")
		(comment 1 "Grand Teton / footprints 4524-4529 of 9728")
	)
	(layers
		(0 "F.Cu" signal "TOP")
		(4 "In1.Cu" signal "GND")
		(6 "In2.Cu" signal "VCC")
		(8 "In3.Cu" signal "VCC1")
		(10 "In4.Cu" signal "GND1")
		(12 "In5.Cu" signal "IN1")
		(14 "In6.Cu" signal "GND2")
		(16 "In7.Cu" signal "IN2")
		(18 "In8.Cu" signal "GND3")
		(20 "In9.Cu" signal "IN3")
		(22 "In10.Cu" signal "GND4")
		(24 "In11.Cu" signal "IN4")
		(26 "In12.Cu" signal "GND5")
		(28 "In13.Cu" signal "IN5")
		(30 "In14.Cu" signal "GND6")
		(32 "In15.Cu" signal "IN6")
		(34 "In16.Cu" signal "GND7")
		(2 "B.Cu" signal "BOTTOM")
		(9 "F.Adhes" user "F.Adhesive")
		(11 "B.Adhes" user "B.Adhesive")
		(13 "F.Paste" user "Package Geometry/Pastemask Top")
		(15 "B.Paste" user "Package Geometry/Pastemask Bottom")
		(5 "F.SilkS" user "Ref Des/Silkscreen Top")
		(7 "B.SilkS" user "Ref Des/Silkscreen Bottom")
		(1 "F.Mask" user "Board Geometry/Soldermask Top")
		(3 "B.Mask" user "Board Geometry/Soldermask Bottom")
		(17 "Dwgs.User" user "User.Drawings")
		(19 "Cmts.User" user "User.Comments")
		(21 "Eco1.User" user "User.Eco1")
		(23 "Eco2.User" user "User.Eco2")
		(25 "Edge.Cuts" user "Board Geometry/Outline")
		(27 "Margin" user)
		(31 "F.CrtYd" user "Package Geometry/Place Bound Top")
		(29 "B.CrtYd" user "Package Geometry/Place Bound Bottom")
		(35 "F.Fab" user "Ref Des/Assembly Top")
		(33 "B.Fab" user "Ref Des/Assembly Bottom")
	)
	(footprint ""
		(layer "F.Cu")
		(at 445.318134 -411.500066 -90)
		(property "Reference" "C3653"
			(at 0 0 270)
			(layer "F.SilkS")
			(hide yes)
			(effects
				(font
					(size 1.27 1.27)
				)
			)
		)
		(property "Value" ""
			(at 0 0 270)
			(layer "F.Fab")
			(effects
				(font
					(size 1.27 1.27)
				)
			)
		)
		(duplicate_pad_numbers_are_jumpers no)
		(fp_line
			(start -0.7874 0.4064)
			(end -0.7874 -0.4064)
			(stroke
				(width 0.1524)
				(type default)
			)
			(layer "F.SilkS")
		)
		(fp_line
			(start 0.7874 0.4064)
			(end -0.7874 0.4064)
			(stroke
				(width 0.1524)
				(type default)
			)
			(layer "F.SilkS")
		)
		(fp_line
			(start -0.7874 -0.4064)
			(end 0.7874 -0.4064)
			(stroke
				(width 0.1524)
				(type default)
			)
			(layer "F.SilkS")
		)
		(fp_line
			(start 0.7874 -0.4064)
			(end 0.7874 0.4064)
			(stroke
				(width 0.1524)
				(type default)
			)
			(layer "F.SilkS")
		)
		(fp_line
			(start -0.67945 0.3048)
			(end -0.67945 -0.305054)
			(stroke
				(width 0.1)
				(type default)
			)
			(layer "F.Fab")
		)
		(fp_line
			(start -0.12065 0.3048)
			(end -0.67945 0.3048)
			(stroke
				(width 0.1)
				(type default)
			)
			(layer "F.Fab")
		)
		(fp_line
			(start 0.120396 0.3048)
			(end 0.120396 0.2794)
			(stroke
				(width 0.1)
				(type default)
			)
			(layer "F.Fab")
		)
		(fp_line
			(start 0.67945 0.3048)
			(end 0.120396 0.3048)
			(stroke
				(width 0.1)
				(type default)
			)
			(layer "F.Fab")
		)
		(fp_line
			(start -0.12065 0.2794)
			(end -0.12065 0.3048)
			(stroke
				(width 0.1)
				(type default)
			)
			(layer "F.Fab")
		)
		(fp_line
			(start 0.120396 0.2794)
			(end -0.12065 0.2794)
			(stroke
				(width 0.1)
				(type default)
			)
			(layer "F.Fab")
		)
		(fp_line
			(start -0.12065 -0.2794)
			(end 0.12065 -0.2794)
			(stroke
				(width 0.1)
				(type default)
			)
			(layer "F.Fab")
		)
		(fp_line
			(start 0.12065 -0.2794)
			(end 0.12065 -0.3048)
			(stroke
				(width 0.1)
				(type default)
			)
			(layer "F.Fab")
		)
		(fp_line
			(start 0.12065 -0.3048)
			(end 0.67945 -0.3048)
			(stroke
				(width 0.1)
				(type default)
			)
			(layer "F.Fab")
		)
		(fp_line
			(start 0.67945 -0.3048)
			(end 0.67945 0.3048)
			(stroke
				(width 0.1)
				(type default)
			)
			(layer "F.Fab")
		)
		(fp_line
			(start -0.67945 -0.305054)
			(end -0.12065 -0.305054)
			(stroke
				(width 0.1)
				(type default)
			)
			(layer "F.Fab")
		)
		(fp_line
			(start -0.12065 -0.305054)
			(end -0.12065 -0.2794)
			(stroke
				(width 0.1)
				(type default)
			)
			(layer "F.Fab")
		)
		(pad "1" smd circle
			(at -0.40005 0 270)
			(size 0 0)
			(layers "F.Cu" "F.Mask" "F.Paste")
			(net "P3V3_AUX")
		)
		(pad "2" smd circle
			(at 0.40005 0 270)
			(size 0 0)
			(layers "F.Cu" "F.Mask" "F.Paste")
			(net "GND")
		)
	)
	(footprint ""
		(layer "F.Cu")
		(at 217.235786 -214.238586 180)
		(property "Reference" "R1503"
			(at 0 0 180)
			(layer "F.SilkS")
			(hide yes)
			(effects
				(font
					(size 1.27 1.27)
				)
			)
		)
		(property "Value" ""
			(at 0 0 180)
			(layer "F.Fab")
			(effects
				(font
					(size 1.27 1.27)
				)
			)
		)
		(duplicate_pad_numbers_are_jumpers no)
		(fp_line
			(start 0.7874 0.4064)
			(end -0.7874 0.4064)
			(stroke
				(width 0.1524)
				(type default)
			)
			(layer "F.SilkS")
		)
		(fp_line
			(start 0.7874 -0.4064)
			(end 0.7874 0.4064)
			(stroke
				(width 0.1524)
				(type default)
			)
			(layer "F.SilkS")
		)
		(fp_line
			(start -0.7874 0.4064)
			(end -0.7874 -0.4064)
			(stroke
				(width 0.1524)
				(type default)
			)
			(layer "F.SilkS")
		)
		(fp_line
			(start -0.7874 -0.4064)
			(end 0.7874 -0.4064)
			(stroke
				(width 0.1524)
				(type default)
			)
			(layer "F.SilkS")
		)
		(fp_line
			(start 0.67945 0.3048)
			(end 0.120396 0.3048)
			(stroke
				(width 0.1)
				(type default)
			)
			(layer "F.Fab")
		)
		(fp_line
			(start 0.67945 -0.3048)
			(end 0.67945 0.3048)
			(stroke
				(width 0.1)
				(type default)
			)
			(layer "F.Fab")
		)
		(fp_line
			(start 0.12065 -0.2794)
			(end 0.12065 -0.3048)
			(stroke
				(width 0.1)
				(type default)
			)
			(layer "F.Fab")
		)
		(fp_line
			(start 0.12065 -0.3048)
			(end 0.67945 -0.3048)
			(stroke
				(width 0.1)
				(type default)
			)
			(layer "F.Fab")
		)
		(fp_line
			(start 0.120396 0.3048)
			(end 0.120396 0.2794)
			(stroke
				(width 0.1)
				(type default)
			)
			(layer "F.Fab")
		)
		(fp_line
			(start 0.120396 0.2794)
			(end -0.12065 0.2794)
			(stroke
				(width 0.1)
				(type default)
			)
			(layer "F.Fab")
		)
		(fp_line
			(start -0.12065 0.3048)
			(end -0.67945 0.3048)
			(stroke
				(width 0.1)
				(type default)
			)
			(layer "F.Fab")
		)
		(fp_line
			(start -0.12065 0.2794)
			(end -0.12065 0.3048)
			(stroke
				(width 0.1)
				(type default)
			)
			(layer "F.Fab")
		)
		(fp_line
			(start -0.12065 -0.2794)
			(end 0.12065 -0.2794)
			(stroke
				(width 0.1)
				(type default)
			)
			(layer "F.Fab")
		)
		(fp_line
			(start -0.12065 -0.305054)
			(end -0.12065 -0.2794)
			(stroke
				(width 0.1)
				(type default)
			)
			(layer "F.Fab")
		)
		(fp_line
			(start -0.67945 0.3048)
			(end -0.67945 -0.305054)
			(stroke
				(width 0.1)
				(type default)
			)
			(layer "F.Fab")
		)
		(fp_line
			(start -0.67945 -0.305054)
			(end -0.12065 -0.305054)
			(stroke
				(width 0.1)
				(type default)
			)
			(layer "F.Fab")
		)
		(pad "1" smd circle
			(at -0.40005 0 180)
			(size 0 0)
			(layers "F.Cu" "F.Mask" "F.Paste")
			(net "SMB_NIC6_SDA")
		)
		(pad "2" smd circle
			(at 0.40005 0 180)
			(size 0 0)
			(layers "F.Cu" "F.Mask" "F.Paste")
			(net "SMB_NIC6_R_SDA")
		)
	)
	(footprint ""
		(layer "F.Cu")
		(at 373.364506 -29.079952 180)
		(property "Reference" "R6210"
			(at 0 0 180)
			(layer "F.SilkS")
			(hide yes)
			(effects
				(font
					(size 1.27 1.27)
				)
			)
		)
		(property "Value" ""
			(at 0 0 180)
			(layer "F.Fab")
			(effects
				(font
					(size 1.27 1.27)
				)
			)
		)
		(duplicate_pad_numbers_are_jumpers no)
		(fp_line
			(start 0.7874 0.4064)
			(end -0.7874 0.4064)
			(stroke
				(width 0.1524)
				(type default)
			)
			(layer "F.SilkS")
		)
		(fp_line
			(start 0.7874 -0.4064)
			(end 0.7874 0.4064)
			(stroke
				(width 0.1524)
				(type default)
			)
			(layer "F.SilkS")
		)
		(fp_line
			(start -0.7874 0.4064)
			(end -0.7874 -0.4064)
			(stroke
				(width 0.1524)
				(type default)
			)
			(layer "F.SilkS")
		)
		(fp_line
			(start -0.7874 -0.4064)
			(end 0.7874 -0.4064)
			(stroke
				(width 0.1524)
				(type default)
			)
			(layer "F.SilkS")
		)
		(fp_line
			(start 0.67945 0.3048)
			(end 0.120396 0.3048)
			(stroke
				(width 0.1)
				(type default)
			)
			(layer "F.Fab")
		)
		(fp_line
			(start 0.67945 -0.3048)
			(end 0.67945 0.3048)
			(stroke
				(width 0.1)
				(type default)
			)
			(layer "F.Fab")
		)
		(fp_line
			(start 0.12065 -0.2794)
			(end 0.12065 -0.3048)
			(stroke
				(width 0.1)
				(type default)
			)
			(layer "F.Fab")
		)
		(fp_line
			(start 0.12065 -0.3048)
			(end 0.67945 -0.3048)
			(stroke
				(width 0.1)
				(type default)
			)
			(layer "F.Fab")
		)
		(fp_line
			(start 0.120396 0.3048)
			(end 0.120396 0.2794)
			(stroke
				(width 0.1)
				(type default)
			)
			(layer "F.Fab")
		)
		(fp_line
			(start 0.120396 0.2794)
			(end -0.12065 0.2794)
			(stroke
				(width 0.1)
				(type default)
			)
			(layer "F.Fab")
		)
		(fp_line
			(start -0.12065 0.3048)
			(end -0.67945 0.3048)
			(stroke
				(width 0.1)
				(type default)
			)
			(layer "F.Fab")
		)
		(fp_line
			(start -0.12065 0.2794)
			(end -0.12065 0.3048)
			(stroke
				(width 0.1)
				(type default)
			)
			(layer "F.Fab")
		)
		(fp_line
			(start -0.12065 -0.2794)
			(end 0.12065 -0.2794)
			(stroke
				(width 0.1)
				(type default)
			)
			(layer "F.Fab")
		)
		(fp_line
			(start -0.12065 -0.305054)
			(end -0.12065 -0.2794)
			(stroke
				(width 0.1)
				(type default)
			)
			(layer "F.Fab")
		)
		(fp_line
			(start -0.67945 0.3048)
			(end -0.67945 -0.305054)
			(stroke
				(width 0.1)
				(type default)
			)
			(layer "F.Fab")
		)
		(fp_line
			(start -0.67945 -0.305054)
			(end -0.12065 -0.305054)
			(stroke
				(width 0.1)
				(type default)
			)
			(layer "F.Fab")
		)
		(pad "1" smd circle
			(at -0.40005 0 180)
			(size 0 0)
			(layers "F.Cu" "F.Mask" "F.Paste")
			(net "GND")
		)
		(pad "2" smd circle
			(at 0.40005 0 180)
			(size 0 0)
			(layers "F.Cu" "F.Mask" "F.Paste")
			(net "SSD12_PWRDIS_R")
		)
	)
	(footprint ""
		(layer "F.Cu")
		(at 208.782158 -237.127034)
		(property "Reference" "C2708"
			(at 0 0 0)
			(layer "F.SilkS")
			(hide yes)
			(effects
				(font
					(size 1.27 1.27)
				)
			)
		)
		(property "Value" ""
			(at 0 0 0)
			(layer "F.Fab")
			(effects
				(font
					(size 1.27 1.27)
				)
			)
		)
		(duplicate_pad_numbers_are_jumpers no)
		(fp_line
			(start -0.7874 -0.4064)
			(end 0.7874 -0.4064)
			(stroke
				(width 0.1524)
				(type default)
			)
			(layer "F.SilkS")
		)
		(fp_line
			(start -0.7874 0.4064)
			(end -0.7874 -0.4064)
			(stroke
				(width 0.1524)
				(type default)
			)
			(layer "F.SilkS")
		)
		(fp_line
			(start 0.7874 -0.4064)
			(end 0.7874 0.4064)
			(stroke
				(width 0.1524)
				(type default)
			)
			(layer "F.SilkS")
		)
		(fp_line
			(start 0.7874 0.4064)
			(end -0.7874 0.4064)
			(stroke
				(width 0.1524)
				(type default)
			)
			(layer "F.SilkS")
		)
		(fp_line
			(start -0.67945 -0.305054)
			(end -0.12065 -0.305054)
			(stroke
				(width 0.1)
				(type default)
			)
			(layer "F.Fab")
		)
		(fp_line
			(start -0.67945 0.3048)
			(end -0.67945 -0.305054)
			(stroke
				(width 0.1)
				(type default)
			)
			(layer "F.Fab")
		)
		(fp_line
			(start -0.12065 -0.305054)
			(end -0.12065 -0.2794)
			(stroke
				(width 0.1)
				(type default)
			)
			(layer "F.Fab")
		)
		(fp_line
			(start -0.12065 -0.2794)
			(end 0.12065 -0.2794)
			(stroke
				(width 0.1)
				(type default)
			)
			(layer "F.Fab")
		)
		(fp_line
			(start -0.12065 0.2794)
			(end -0.12065 0.3048)
			(stroke
				(width 0.1)
				(type default)
			)
			(layer "F.Fab")
		)
		(fp_line
			(start -0.12065 0.3048)
			(end -0.67945 0.3048)
			(stroke
				(width 0.1)
				(type default)
			)
			(layer "F.Fab")
		)
		(fp_line
			(start 0.120396 0.2794)
			(end -0.12065 0.2794)
			(stroke
				(width 0.1)
				(type default)
			)
			(layer "F.Fab")
		)
		(fp_line
			(start 0.120396 0.3048)
			(end 0.120396 0.2794)
			(stroke
				(width 0.1)
				(type default)
			)
			(layer "F.Fab")
		)
		(fp_line
			(start 0.12065 -0.3048)
			(end 0.67945 -0.3048)
			(stroke
				(width 0.1)
				(type default)
			)
			(layer "F.Fab")
		)
		(fp_line
			(start 0.12065 -0.2794)
			(end 0.12065 -0.3048)
			(stroke
				(width 0.1)
				(type default)
			)
			(layer "F.Fab")
		)
		(fp_line
			(start 0.67945 -0.3048)
			(end 0.67945 0.3048)
			(stroke
				(width 0.1)
				(type default)
			)
			(layer "F.Fab")
		)
		(fp_line
			(start 0.67945 0.3048)
			(end 0.120396 0.3048)
			(stroke
				(width 0.1)
				(type default)
			)
			(layer "F.Fab")
		)
		(pad "1" smd circle
			(at -0.40005 0)
			(size 0 0)
			(layers "F.Cu" "F.Mask" "F.Paste")
			(net "GND")
		)
		(pad "2" smd circle
			(at 0.40005 0)
			(size 0 0)
			(layers "F.Cu" "F.Mask" "F.Paste")
			(net "P1V8_PEX")
		)
	)
	(footprint ""
		(layer "F.Cu")
		(at 104.728772 -92.366846 -90)
		(property "Reference" "R1130"
			(at 0 0 270)
			(layer "F.SilkS")
			(hide yes)
			(effects
				(font
					(size 1.27 1.27)
				)
			)
		)
		(property "Value" ""
			(at 0 0 270)
			(layer "F.Fab")
			(effects
				(font
					(size 1.27 1.27)
				)
			)
		)
		(duplicate_pad_numbers_are_jumpers no)
		(fp_line
			(start -0.7874 0.4064)
			(end -0.7874 -0.4064)
			(stroke
				(width 0.1524)
				(type default)
			)
			(layer "F.SilkS")
		)
		(fp_line
			(start 0.7874 0.4064)
			(end -0.7874 0.4064)
			(stroke
				(width 0.1524)
				(type default)
			)
			(layer "F.SilkS")
		)
		(fp_line
			(start -0.7874 -0.4064)
			(end 0.7874 -0.4064)
			(stroke
				(width 0.1524)
				(type default)
			)
			(layer "F.SilkS")
		)
		(fp_line
			(start 0.7874 -0.4064)
			(end 0.7874 0.4064)
			(stroke
				(width 0.1524)
				(type default)
			)
			(layer "F.SilkS")
		)
		(fp_line
			(start -0.67945 0.3048)
			(end -0.67945 -0.305054)
			(stroke
				(width 0.1)
				(type default)
			)
			(layer "F.Fab")
		)
		(fp_line
			(start -0.12065 0.3048)
			(end -0.67945 0.3048)
			(stroke
				(width 0.1)
				(type default)
			)
			(layer "F.Fab")
		)
		(fp_line
			(start 0.120396 0.3048)
			(end 0.120396 0.2794)
			(stroke
				(width 0.1)
				(type default)
			)
			(layer "F.Fab")
		)
		(fp_line
			(start 0.67945 0.3048)
			(end 0.120396 0.3048)
			(stroke
				(width 0.1)
				(type default)
			)
			(layer "F.Fab")
		)
		(fp_line
			(start -0.12065 0.2794)
			(end -0.12065 0.3048)
			(stroke
				(width 0.1)
				(type default)
			)
			(layer "F.Fab")
		)
		(fp_line
			(start 0.120396 0.2794)
			(end -0.12065 0.2794)
			(stroke
				(width 0.1)
				(type default)
			)
			(layer "F.Fab")
		)
		(fp_line
			(start -0.12065 -0.2794)
			(end 0.12065 -0.2794)
			(stroke
				(width 0.1)
				(type default)
			)
			(layer "F.Fab")
		)
		(fp_line
			(start 0.12065 -0.2794)
			(end 0.12065 -0.3048)
			(stroke
				(width 0.1)
				(type default)
			)
			(layer "F.Fab")
		)
		(fp_line
			(start 0.12065 -0.3048)
			(end 0.67945 -0.3048)
			(stroke
				(width 0.1)
				(type default)
			)
			(layer "F.Fab")
		)
		(fp_line
			(start 0.67945 -0.3048)
			(end 0.67945 0.3048)
			(stroke
				(width 0.1)
				(type default)
			)
			(layer "F.Fab")
		)
		(fp_line
			(start -0.67945 -0.305054)
			(end -0.12065 -0.305054)
			(stroke
				(width 0.1)
				(type default)
			)
			(layer "F.Fab")
		)
		(fp_line
			(start -0.12065 -0.305054)
			(end -0.12065 -0.2794)
			(stroke
				(width 0.1)
				(type default)
			)
			(layer "F.Fab")
		)
		(pad "1" smd circle
			(at -0.40005 0 270)
			(size 0 0)
			(layers "F.Cu" "F.Mask" "F.Paste")
			(net "P3V3")
		)
		(pad "2" smd circle
			(at 0.40005 0 270)
			(size 0 0)
			(layers "F.Cu" "F.Mask" "F.Paste")
			(net "PU_9ZXL0851_0_7_HBW")
		)
	)
	(footprint ""
		(layer "F.Cu")
		(at 455.009758 -276.316694)
		(property "Reference" "R811"
			(at 0 0 0)
			(layer "F.SilkS")
			(hide yes)
			(effects
				(font
					(size 1.27 1.27)
				)
			)
		)
		(property "Value" ""
			(at 0 0 0)
			(layer "F.Fab")
			(effects
				(font
					(size 1.27 1.27)
				)
			)
		)
		(duplicate_pad_numbers_are_jumpers no)
		(fp_line
			(start -0.7874 -0.4064)
			(end 0.7874 -0.4064)
			(stroke
				(width 0.1524)
				(type default)
			)
			(layer "F.SilkS")
		)
		(fp_line
			(start -0.7874 0.4064)
			(end -0.7874 -0.4064)
			(stroke
				(width 0.1524)
				(type default)
			)
			(layer "F.SilkS")
		)
		(fp_line
			(start 0.7874 -0.4064)
			(end 0.7874 0.4064)
			(stroke
				(width 0.1524)
				(type default)
			)
			(layer "F.SilkS")
		)
		(fp_line
			(start 0.7874 0.4064)
			(end -0.7874 0.4064)
			(stroke
				(width 0.1524)
				(type default)
			)
			(layer "F.SilkS")
		)
		(fp_line
			(start -0.67945 -0.305054)
			(end -0.12065 -0.305054)
			(stroke
				(width 0.1)
				(type default)
			)
			(layer "F.Fab")
		)
		(fp_line
			(start -0.67945 0.3048)
			(end -0.67945 -0.305054)
			(stroke
				(width 0.1)
				(type default)
			)
			(layer "F.Fab")
		)
		(fp_line
			(start -0.12065 -0.305054)
			(end -0.12065 -0.2794)
			(stroke
				(width 0.1)
				(type default)
			)
			(layer "F.Fab")
		)
		(fp_line
			(start -0.12065 -0.2794)
			(end 0.12065 -0.2794)
			(stroke
				(width 0.1)
				(type default)
			)
			(layer "F.Fab")
		)
		(fp_line
			(start -0.12065 0.2794)
			(end -0.12065 0.3048)
			(stroke
				(width 0.1)
				(type default)
			)
			(layer "F.Fab")
		)
		(fp_line
			(start -0.12065 0.3048)
			(end -0.67945 0.3048)
			(stroke
				(width 0.1)
				(type default)
			)
			(layer "F.Fab")
		)
		(fp_line
			(start 0.120396 0.2794)
			(end -0.12065 0.2794)
			(stroke
				(width 0.1)
				(type default)
			)
			(layer "F.Fab")
		)
		(fp_line
			(start 0.120396 0.3048)
			(end 0.120396 0.2794)
			(stroke
				(width 0.1)
				(type default)
			)
			(layer "F.Fab")
		)
		(fp_line
			(start 0.12065 -0.3048)
			(end 0.67945 -0.3048)
			(stroke
				(width 0.1)
				(type default)
			)
			(layer "F.Fab")
		)
		(fp_line
			(start 0.12065 -0.2794)
			(end 0.12065 -0.3048)
			(stroke
				(width 0.1)
				(type default)
			)
			(layer "F.Fab")
		)
		(fp_line
			(start 0.67945 -0.3048)
			(end 0.67945 0.3048)
			(stroke
				(width 0.1)
				(type default)
			)
			(layer "F.Fab")
		)
		(fp_line
			(start 0.67945 0.3048)
			(end 0.120396 0.3048)
			(stroke
				(width 0.1)
				(type default)
			)
			(layer "F.Fab")
		)
		(pad "1" smd circle
			(at -0.40005 0)
			(size 0 0)
			(layers "F.Cu" "F.Mask" "F.Paste")
			(net "P1V25_PEX3")
		)
		(pad "2" smd circle
			(at 0.40005 0)
			(size 0 0)
			(layers "F.Cu" "F.Mask" "F.Paste")
			(net "P12V_PEX3_P1V25_VIN_N")
		)
	)
)
